# T6G (Grand Teton) — schematic netlist excerpt (pin names and nets, part order shuffled) for the footprints in the layout excerpt that follows; sources: Cadence DE-HDL packaged netlist, KiCad conversion of 04192023_DAF0TMB3IC0_F0TG_MB_C_brd_V02_OCP.brd

C876  Q_CAP_DIFFBUS  DIFF BUS_0.22UF 6.3V 20% X6S  pkg C0201  page 64 : \1\ = P5E_CPU0_P3_TX_C_DN<12> ; \2\ = P5E_CPU0_P3_TX_DN<12>
R1856  Q_RES  100 1% CHIP  pkg 0402LF  page 152 : A = FM_SCM_PRSNT1_N ; B = FM_SCM_PRSNT1_R_N

Y9  Q_XTAL_4P_13BI_24GND  26MHZ MISC  pkg X_4S_8Z25000020_2-5X2  page 176
  X1  = XTAL_USB_CPU0_HUB1_XIN
  G1  = GND
  X2  = XTAL_USB_CPU0_HUB1_XOUT
  G2  = GND

(kicad_pcb
	(version 20260206)
	(generator "pcbnew")
	(generator_version "10.0")
	(general
		(thickness 1.6)
		(legacy_teardrops no)
	)
	(paper "A4")
	(title_block
		(title "04192023_DAF0TMB3IC0_F0TG_MB_C_brd_V02_OCP.brd")
		(comment 1 "Grand Teton / footprints 2998-3000 of 8354")
	)
	(layers
		(0 "F.Cu" signal "TOP")
		(4 "In1.Cu" signal "GND")
		(6 "In2.Cu" signal "IN1")
		(8 "In3.Cu" signal "GND1")
		(10 "In4.Cu" signal "IN2")
		(12 "In5.Cu" signal "GND2")
		(14 "In6.Cu" signal "IN3")
		(16 "In7.Cu" signal "GND3")
		(18 "In8.Cu" signal "VCC")
		(20 "In9.Cu" signal "VCC1")
		(22 "In10.Cu" signal "GND4")
		(24 "In11.Cu" signal "IN4")
		(26 "In12.Cu" signal "GND5")
		(28 "In13.Cu" signal "IN5")
		(30 "In14.Cu" signal "GND6")
		(32 "In15.Cu" signal "IN6")
		(34 "In16.Cu" signal "GND7")
		(2 "B.Cu" signal "BOTTOM")
		(9 "F.Adhes" user "F.Adhesive")
		(11 "B.Adhes" user "B.Adhesive")
		(13 "F.Paste" user "Package Geometry/Pastemask Top")
		(15 "B.Paste" user "Package Geometry/Pastemask Bottom")
		(5 "F.SilkS" user "Ref Des/Silkscreen Top")
		(7 "B.SilkS" user "Ref Des/Silkscreen Bottom")
		(1 "F.Mask" user "Board Geometry/Soldermask Top")
		(3 "B.Mask" user "Board Geometry/Soldermask Bottom")
		(17 "Dwgs.User" user "User.Drawings")
		(19 "Cmts.User" user "User.Comments")
		(21 "Eco1.User" user "User.Eco1")
		(23 "Eco2.User" user "User.Eco2")
		(25 "Edge.Cuts" user "Board Geometry/Outline")
		(27 "Margin" user)
		(31 "F.CrtYd" user "Package Geometry/Place Bound Top")
		(29 "B.CrtYd" user "Package Geometry/Place Bound Bottom")
		(35 "F.Fab" user "Ref Des/Assembly Top")
		(33 "B.Fab" user "Ref Des/Assembly Bottom")
	)
	(footprint ""
		(layer "F.Cu")
		(at 389.127492 -378.95403 -90)
		(property "Reference" "C876"
			(at 0 0 270)
			(layer "F.SilkS")
			(hide yes)
			(effects
				(font
					(size 1.27 1.27)
				)
			)
		)
		(property "Value" ""
			(at 0 0 270)
			(layer "F.Fab")
			(effects
				(font
					(size 1.27 1.27)
				)
			)
		)
		(duplicate_pad_numbers_are_jumpers no)
		(fp_line
			(start -0.299974 0.150114)
			(end -0.299974 -0.150114)
			(stroke
				(width 0.1)
				(type default)
			)
			(layer "F.Fab")
		)
		(fp_line
			(start 0.299974 0.150114)
			(end -0.299974 0.150114)
			(stroke
				(width 0.1)
				(type default)
			)
			(layer "F.Fab")
		)
		(fp_line
			(start -0.299974 -0.150114)
			(end 0.299974 -0.150114)
			(stroke
				(width 0.1)
				(type default)
			)
			(layer "F.Fab")
		)
		(fp_line
			(start 0.299974 -0.150114)
			(end 0.299974 0.150114)
			(stroke
				(width 0.1)
				(type default)
			)
			(layer "F.Fab")
		)
		(pad "1" smd rect
			(at -0.2667 0 270)
			(size 0.3048 0.381)
			(layers "F.Cu" "F.Mask" "F.Paste")
			(net "P5E_CPU0_P3_TX_C_DN<12>")
		)
		(pad "2" smd rect
			(at 0.2667 0 270)
			(size 0.3048 0.381)
			(layers "F.Cu" "F.Mask" "F.Paste")
			(net "P5E_CPU0_P3_TX_DN<12>")
		)
	)
	(footprint ""
		(layer "F.Cu")
		(at 189.79769 -36.0807)
		(property "Reference" "R1856"
			(at 0 0 0)
			(layer "F.SilkS")
			(hide yes)
			(effects
				(font
					(size 1.27 1.27)
				)
			)
		)
		(property "Value" ""
			(at 0 0 0)
			(layer "F.Fab")
			(effects
				(font
					(size 1.27 1.27)
				)
			)
		)
		(duplicate_pad_numbers_are_jumpers no)
		(fp_line
			(start -0.7874 -0.4064)
			(end 0.7874 -0.4064)
			(stroke
				(width 0.1524)
				(type default)
			)
			(layer "F.SilkS")
		)
		(fp_line
			(start -0.7874 0.4064)
			(end -0.7874 -0.4064)
			(stroke
				(width 0.1524)
				(type default)
			)
			(layer "F.SilkS")
		)
		(fp_line
			(start 0.7874 -0.4064)
			(end 0.7874 0.4064)
			(stroke
				(width 0.1524)
				(type default)
			)
			(layer "F.SilkS")
		)
		(fp_line
			(start 0.7874 0.4064)
			(end -0.7874 0.4064)
			(stroke
				(width 0.1524)
				(type default)
			)
			(layer "F.SilkS")
		)
		(fp_line
			(start -0.67945 -0.305054)
			(end -0.12065 -0.305054)
			(stroke
				(width 0.1)
				(type default)
			)
			(layer "F.Fab")
		)
		(fp_line
			(start -0.67945 0.3048)
			(end -0.67945 -0.305054)
			(stroke
				(width 0.1)
				(type default)
			)
			(layer "F.Fab")
		)
		(fp_line
			(start -0.12065 -0.305054)
			(end -0.12065 -0.2794)
			(stroke
				(width 0.1)
				(type default)
			)
			(layer "F.Fab")
		)
		(fp_line
			(start -0.12065 -0.2794)
			(end 0.12065 -0.2794)
			(stroke
				(width 0.1)
				(type default)
			)
			(layer "F.Fab")
		)
		(fp_line
			(start -0.12065 0.2794)
			(end -0.12065 0.3048)
			(stroke
				(width 0.1)
				(type default)
			)
			(layer "F.Fab")
		)
		(fp_line
			(start -0.12065 0.3048)
			(end -0.67945 0.3048)
			(stroke
				(width 0.1)
				(type default)
			)
			(layer "F.Fab")
		)
		(fp_line
			(start 0.120396 0.2794)
			(end -0.12065 0.2794)
			(stroke
				(width 0.1)
				(type default)
			)
			(layer "F.Fab")
		)
		(fp_line
			(start 0.120396 0.3048)
			(end 0.120396 0.2794)
			(stroke
				(width 0.1)
				(type default)
			)
			(layer "F.Fab")
		)
		(fp_line
			(start 0.12065 -0.3048)
			(end 0.67945 -0.3048)
			(stroke
				(width 0.1)
				(type default)
			)
			(layer "F.Fab")
		)
		(fp_line
			(start 0.12065 -0.2794)
			(end 0.12065 -0.3048)
			(stroke
				(width 0.1)
				(type default)
			)
			(layer "F.Fab")
		)
		(fp_line
			(start 0.67945 -0.3048)
			(end 0.67945 0.3048)
			(stroke
				(width 0.1)
				(type default)
			)
			(layer "F.Fab")
		)
		(fp_line
			(start 0.67945 0.3048)
			(end 0.120396 0.3048)
			(stroke
				(width 0.1)
				(type default)
			)
			(layer "F.Fab")
		)
		(pad "1" smd circle
			(at -0.40005 0)
			(size 0 0)
			(layers "F.Cu" "F.Mask" "F.Paste")
			(net "FM_SCM_PRSNT1_N")
		)
		(pad "2" smd circle
			(at 0.40005 0)
			(size 0 0)
			(layers "F.Cu" "F.Mask" "F.Paste")
			(net "FM_SCM_PRSNT1_R_N")
		)
	)
	(footprint ""
		(layer "F.Cu")
		(at 124.46 -28.854654 180)
		(property "Reference" "Y9"
			(at 1.37668 -2.9845 0)
			(unlocked yes)
			(layer "F.SilkS")
			(effects
				(font
					(size 0.7874 0.5842)
					(thickness 0.1524)
				)
				(justify left)
			)
		)
		(property "Value" ""
			(at 0 0 180)
			(layer "F.Fab")
			(effects
				(font
					(size 1.27 1.27)
				)
			)
		)
		(duplicate_pad_numbers_are_jumpers no)
		(fp_line
			(start 1.380236 1.579372)
			(end 1.380236 -1.579372)
			(stroke
				(width 0.1524)
				(type default)
			)
			(layer "F.SilkS")
		)
		(fp_line
			(start 1.380236 -1.579372)
			(end -1.380236 -1.579372)
			(stroke
				(width 0.1524)
				(type default)
			)
			(layer "F.SilkS")
		)
		(fp_line
			(start -1.380236 1.579372)
			(end 1.380236 1.579372)
			(stroke
				(width 0.1524)
				(type default)
			)
			(layer "F.SilkS")
		)
		(fp_line
			(start -1.380236 -1.579372)
			(end -1.380236 1.579372)
			(stroke
				(width 0.1524)
				(type default)
			)
			(layer "F.SilkS")
		)
		(fp_poly
			(pts
				(xy -0.774446 -1.816354) (xy -1.155446 -2.578354) (xy -0.393446 -2.578354)
			)
			(stroke
				(width 0)
				(type default)
			)
			(fill yes)
			(layer "F.SilkS")
		)
		(fp_line
			(start 1.050036 1.299972)
			(end 1.050036 -1.299972)
			(stroke
				(width 0.1)
				(type default)
			)
			(layer "F.Fab")
		)
		(fp_line
			(start 1.050036 -1.299972)
			(end -1.050036 -1.299972)
			(stroke
				(width 0.1)
				(type default)
			)
			(layer "F.Fab")
		)
		(fp_line
			(start -1.050036 1.299972)
			(end 1.050036 1.299972)
			(stroke
				(width 0.1)
				(type default)
			)
			(layer "F.Fab")
		)
		(fp_line
			(start -1.050036 -1.299972)
			(end -1.050036 1.299972)
			(stroke
				(width 0.1)
				(type default)
			)
			(layer "F.Fab")
		)
		(fp_poly
			(pts
				(xy -2.3114 -1.306068) (xy -2.3114 -0.544068) (xy -1.5494 -0.925068)
			)
			(stroke
				(width 0)
				(type default)
			)
			(fill yes)
			(layer "F.Fab")
		)
		(pad "1" smd rect
			(at -0.774954 -0.925068 180)
			(size 0.9144 1.016)
			(layers "F.Cu" "F.Mask" "F.Paste")
			(net "XTAL_USB_CPU0_HUB1_XIN")
		)
		(pad "2" smd rect
			(at -0.774954 0.925068 180)
			(size 0.9144 1.016)
			(layers "F.Cu" "F.Mask" "F.Paste")
			(net "GND")
		)
		(pad "3" smd rect
			(at 0.774954 0.925068 180)
			(size 0.9144 1.016)
			(layers "F.Cu" "F.Mask" "F.Paste")
			(net "XTAL_USB_CPU0_HUB1_XOUT")
		)
		(pad "4" smd rect
			(at 0.774954 -0.925068 180)
			(size 0.9144 1.016)
			(layers "F.Cu" "F.Mask" "F.Paste")
			(net "GND")
		)
	)
)
